(kicad_pcb
	(version 20260206)
	(generator "pcbnew")
	(generator_version "10.0")
	(general
		(thickness 1.6)
		(legacy_teardrops no)
	)
	(paper "A4")
	(title_block
		(title "04192023_DAF0TMB3IC0_F0TG_MB_C_brd_V02_OCP.brd")
		(comment 1 "Grand Teton / footprints 4966-4972 of 8354")
	)
	(layers
		(0 "F.Cu" signal "TOP")
		(4 "In1.Cu" signal "GND")
		(6 "In2.Cu" signal "IN1")
		(8 "In3.Cu" signal "GND1")
		(10 "In4.Cu" signal "IN2")
		(12 "In5.Cu" signal "GND2")
		(14 "In6.Cu" signal "IN3")
		(16 "In7.Cu" signal "GND3")
		(18 "In8.Cu" signal "VCC")
		(20 "In9.Cu" signal "VCC1")
		(22 "In10.Cu" signal "GND4")
		(24 "In11.Cu" signal "IN4")
		(26 "In12.Cu" signal "GND5")
		(28 "In13.Cu" signal "IN5")
		(30 "In14.Cu" signal "GND6")
		(32 "In15.Cu" signal "IN6")
		(34 "In16.Cu" signal "GND7")
		(2 "B.Cu" signal "BOTTOM")
		(9 "F.Adhes" user "F.Adhesive")
		(11 "B.Adhes" user "B.Adhesive")
		(13 "F.Paste" user "Package Geometry/Pastemask Top")
		(15 "B.Paste" user "Package Geometry/Pastemask Bottom")
		(5 "F.SilkS" user "Ref Des/Silkscreen Top")
		(7 "B.SilkS" user "Ref Des/Silkscreen Bottom")
		(1 "F.Mask" user "Board Geometry/Soldermask Top")
		(3 "B.Mask" user "Board Geometry/Soldermask Bottom")
		(17 "Dwgs.User" user "User.Drawings")
		(19 "Cmts.User" user "User.Comments")
		(21 "Eco1.User" user "User.Eco1")
		(23 "Eco2.User" user "User.Eco2")
		(25 "Edge.Cuts" user "Board Geometry/Outline")
		(27 "Margin" user)
		(31 "F.CrtYd" user "Package Geometry/Place Bound Top")
		(29 "B.CrtYd" user "Package Geometry/Place Bound Bottom")
		(35 "F.Fab" user "Ref Des/Assembly Top")
		(33 "B.Fab" user "Ref Des/Assembly Bottom")
	)
	(footprint ""
		(layer "B.Cu")
		(at 276.520402 -76.110084 180)
		(property "Reference" ""
			(at 0 0 0)
			(layer "B.SilkS")
			(hide yes)
			(effects
				(font
					(size 1.27 1.27)
				)
				(justify mirror)
			)
		)
		(property "Value" ""
			(at 0 0 0)
			(layer "B.Fab")
			(effects
				(font
					(size 1.27 1.27)
				)
				(justify mirror)
			)
		)
		(duplicate_pad_numbers_are_jumpers no)
		(pad "1" smd circle
			(at 0 0)
			(size 0.9906 0.9906)
			(layers "B.Cu" "B.Mask" "B.Paste")
			(net "Net_2235")
		)
		(zone
			(layer "B.Cu")
			(hatch none 0.5)
			(connect_pads
				(clearance 0)
			)
			(min_thickness 0.25)
			(keepout
				(tracks not_allowed)
				(vias allowed)
				(pads allowed)
				(copperpour not_allowed)
				(footprints allowed)
			)
			(placement
				(enabled no)
				(sheetname "")
			)
			(fill
				(thermal_gap 0.5)
				(thermal_bridge_width 0.5)
				(island_removal_mode 0)
			)
			(polygon
				(pts
					(arc
						(start 278.146002 -76.110084)
						(mid 274.894802 -76.110084)
						(end 278.146002 -76.110084)
					)
				)
			)
		)
	)
	(footprint ""
		(layer "B.Cu")
		(at 452.957184 -65.768982 90)
		(property "Reference" "PC1868"
			(at 0 0 90)
			(layer "B.SilkS")
			(hide yes)
			(effects
				(font
					(size 1.27 1.27)
				)
				(justify mirror)
			)
		)
		(property "Value" ""
			(at 0 0 90)
			(layer "B.Fab")
			(effects
				(font
					(size 1.27 1.27)
				)
				(justify mirror)
			)
		)
		(duplicate_pad_numbers_are_jumpers no)
		(fp_line
			(start 1.524 -0.762)
			(end -1.524 -0.762)
			(stroke
				(width 0.1524)
				(type default)
			)
			(layer "B.SilkS")
		)
		(fp_line
			(start -1.524 -0.762)
			(end -1.524 0.762)
			(stroke
				(width 0.1524)
				(type default)
			)
			(layer "B.SilkS")
		)
		(fp_line
			(start 1.524 0.762)
			(end 1.524 -0.762)
			(stroke
				(width 0.1524)
				(type default)
			)
			(layer "B.SilkS")
		)
		(fp_line
			(start -1.524 0.762)
			(end 1.524 0.762)
			(stroke
				(width 0.1524)
				(type default)
			)
			(layer "B.SilkS")
		)
		(fp_line
			(start 1.1049 -0.724916)
			(end 1.1049 0.724916)
			(stroke
				(width 0.1)
				(type default)
			)
			(layer "B.Fab")
		)
		(fp_line
			(start -1.1049 -0.724916)
			(end 1.1049 -0.724916)
			(stroke
				(width 0.1)
				(type default)
			)
			(layer "B.Fab")
		)
		(fp_line
			(start 1.1049 0.724916)
			(end -1.1049 0.724916)
			(stroke
				(width 0.1)
				(type default)
			)
			(layer "B.Fab")
		)
		(fp_line
			(start -1.1049 0.724916)
			(end -1.1049 -0.724916)
			(stroke
				(width 0.1)
				(type default)
			)
			(layer "B.Fab")
		)
		(pad "1" smd rect
			(at 0.889 0 90)
			(size 1.016 1.27)
			(layers "B.Cu" "B.Mask" "B.Paste")
			(net "P3V3_AUX")
		)
		(pad "2" smd rect
			(at -0.889 0 90)
			(size 1.016 1.27)
			(layers "B.Cu" "B.Mask" "B.Paste")
			(net "GND")
		)
	)
	(footprint ""
		(layer "B.Cu")
		(at 101.073204 -424.885358 180)
		(property "Reference" "Q8000"
			(at -1.528826 -2.694686 0)
			(unlocked yes)
			(layer "B.SilkS")
			(effects
				(font
					(size 0.7874 0.5842)
					(thickness 0.1524)
				)
				(justify left mirror)
			)
		)
		(property "Value" ""
			(at 0 0 0)
			(layer "B.Fab")
			(effects
				(font
					(size 1.27 1.27)
				)
				(justify mirror)
			)
		)
		(duplicate_pad_numbers_are_jumpers no)
		(fp_line
			(start 1.332738 1.100074)
			(end 1.332738 -1.100074)
			(stroke
				(width 0.1524)
				(type default)
			)
			(layer "B.SilkS")
		)
		(fp_line
			(start 1.332738 -1.100074)
			(end 0.4826 -1.100074)
			(stroke
				(width 0.1524)
				(type default)
			)
			(layer "B.SilkS")
		)
		(fp_line
			(start 0.4826 -1.100074)
			(end 0 -0.541274)
			(stroke
				(width 0.1524)
				(type default)
			)
			(layer "B.SilkS")
		)
		(fp_line
			(start 0 -0.541274)
			(end -0.4826 -1.100074)
			(stroke
				(width 0.1524)
				(type default)
			)
			(layer "B.SilkS")
		)
		(fp_line
			(start -0.4826 -1.100074)
			(end -1.332738 -1.100074)
			(stroke
				(width 0.1524)
				(type default)
			)
			(layer "B.SilkS")
		)
		(fp_line
			(start -1.332738 1.100074)
			(end 1.332738 1.100074)
			(stroke
				(width 0.1524)
				(type default)
			)
			(layer "B.SilkS")
		)
		(fp_line
			(start -1.332738 -1.100074)
			(end -1.332738 1.100074)
			(stroke
				(width 0.1524)
				(type default)
			)
			(layer "B.SilkS")
		)
		(fp_poly
			(pts
				(xy 2.2352 -0.298958) (xy 2.2352 -1.001014) (xy 1.533144 -0.649986)
			)
			(stroke
				(width 0)
				(type default)
			)
			(fill yes)
			(layer "B.SilkS")
		)
		(fp_line
			(start 0.674878 1.100074)
			(end 0.674878 -1.100074)
			(stroke
				(width 0.1)
				(type default)
			)
			(layer "B.Fab")
		)
		(fp_line
			(start 0.674878 -1.100074)
			(end -0.674878 -1.100074)
			(stroke
				(width 0.1)
				(type default)
			)
			(layer "B.Fab")
		)
		(fp_line
			(start -0.674878 1.100074)
			(end 0.674878 1.100074)
			(stroke
				(width 0.1)
				(type default)
			)
			(layer "B.Fab")
		)
		(fp_line
			(start -0.674878 -1.100074)
			(end -0.674878 1.100074)
			(stroke
				(width 0.1)
				(type default)
			)
			(layer "B.Fab")
		)
		(fp_poly
			(pts
				(xy 2.2352 -0.298958) (xy 2.2352 -1.001014) (xy 1.533144 -0.649986)
			)
			(stroke
				(width 0)
				(type default)
			)
			(fill yes)
			(layer "B.Fab")
		)
		(pad "1" smd rect
			(at 0.94996 -0.649986 270)
			(size 0.4318 0.508)
			(layers "B.Cu" "B.Mask" "B.Paste")
			(net "GND")
		)
		(pad "2" smd rect
			(at 0.94996 0 270)
			(size 0.4318 0.508)
			(layers "B.Cu" "B.Mask" "B.Paste")
			(net "PRSNT_SWB_N")
		)
		(pad "3" smd rect
			(at 0.94996 0.649986 270)
			(size 0.4318 0.508)
			(layers "B.Cu" "B.Mask" "B.Paste")
			(net "PRSNT_SWB_ISO_N")
		)
		(pad "4" smd rect
			(at -0.94996 0.649986 270)
			(size 0.4318 0.508)
			(layers "B.Cu" "B.Mask" "B.Paste")
			(net "GND")
		)
		(pad "5" smd rect
			(at -0.94996 0 270)
			(size 0.4318 0.508)
			(layers "B.Cu" "B.Mask" "B.Paste")
			(net "PRSNT_SWB")
		)
		(pad "6" smd rect
			(at -0.94996 -0.649986 270)
			(size 0.4318 0.508)
			(layers "B.Cu" "B.Mask" "B.Paste")
			(net "PRSNT_SWB")
		)
	)
	(footprint ""
		(layer "B.Cu")
		(at 276.436582 -194.893946 180)
		(property "Reference" "R1572"
			(at 0 0 0)
			(layer "B.SilkS")
			(hide yes)
			(effects
				(font
					(size 1.27 1.27)
				)
				(justify mirror)
			)
		)
		(property "Value" ""
			(at 0 0 0)
			(layer "B.Fab")
			(effects
				(font
					(size 1.27 1.27)
				)
				(justify mirror)
			)
		)
		(duplicate_pad_numbers_are_jumpers no)
		(fp_line
			(start 0.7874 0.4064)
			(end 0.7874 -0.4064)
			(stroke
				(width 0.1524)
				(type default)
			)
			(layer "B.SilkS")
		)
		(fp_line
			(start 0.7874 -0.4064)
			(end -0.7874 -0.4064)
			(stroke
				(width 0.1524)
				(type default)
			)
			(layer "B.SilkS")
		)
		(fp_line
			(start -0.7874 0.4064)
			(end 0.7874 0.4064)
			(stroke
				(width 0.1524)
				(type default)
			)
			(layer "B.SilkS")
		)
		(fp_line
			(start -0.7874 -0.4064)
			(end -0.7874 0.4064)
			(stroke
				(width 0.1524)
				(type default)
			)
			(layer "B.SilkS")
		)
		(fp_line
			(start 0.67945 0.3048)
			(end 0.67945 -0.305054)
			(stroke
				(width 0.1)
				(type default)
			)
			(layer "B.Fab")
		)
		(fp_line
			(start 0.67945 -0.305054)
			(end 0.12065 -0.305054)
			(stroke
				(width 0.1)
				(type default)
			)
			(layer "B.Fab")
		)
		(fp_line
			(start 0.12065 0.3048)
			(end 0.67945 0.3048)
			(stroke
				(width 0.1)
				(type default)
			)
			(layer "B.Fab")
		)
		(fp_line
			(start 0.12065 0.2794)
			(end 0.12065 0.3048)
			(stroke
				(width 0.1)
				(type default)
			)
			(layer "B.Fab")
		)
		(fp_line
			(start 0.12065 -0.2794)
			(end -0.12065 -0.2794)
			(stroke
				(width 0.1)
				(type default)
			)
			(layer "B.Fab")
		)
		(fp_line
			(start 0.12065 -0.305054)
			(end 0.12065 -0.2794)
			(stroke
				(width 0.1)
				(type default)
			)
			(layer "B.Fab")
		)
		(fp_line
			(start -0.120396 0.3048)
			(end -0.120396 0.2794)
			(stroke
				(width 0.1)
				(type default)
			)
			(layer "B.Fab")
		)
		(fp_line
			(start -0.120396 0.2794)
			(end 0.12065 0.2794)
			(stroke
				(width 0.1)
				(type default)
			)
			(layer "B.Fab")
		)
		(fp_line
			(start -0.12065 -0.2794)
			(end -0.12065 -0.3048)
			(stroke
				(width 0.1)
				(type default)
			)
			(layer "B.Fab")
		)
		(fp_line
			(start -0.12065 -0.3048)
			(end -0.67945 -0.3048)
			(stroke
				(width 0.1)
				(type default)
			)
			(layer "B.Fab")
		)
		(fp_line
			(start -0.67945 0.3048)
			(end -0.120396 0.3048)
			(stroke
				(width 0.1)
				(type default)
			)
			(layer "B.Fab")
		)
		(fp_line
			(start -0.67945 -0.3048)
			(end -0.67945 0.3048)
			(stroke
				(width 0.1)
				(type default)
			)
			(layer "B.Fab")
		)
		(pad "1" smd circle
			(at 0.40005 0)
			(size 0 0)
			(layers "B.Cu" "B.Mask" "B.Paste")
			(net "I3C_SPD_DDRAF_CPU0_SCL")
		)
		(pad "2" smd circle
			(at -0.40005 0)
			(size 0 0)
			(layers "B.Cu" "B.Mask" "B.Paste")
			(net "I3C_SPD_DDRE_CPU0_SCL")
		)
	)
	(footprint ""
		(layer "B.Cu")
		(at 33.44545 -426.850302 180)
		(property "Reference" "C1866"
			(at 0 0 0)
			(layer "B.SilkS")
			(hide yes)
			(effects
				(font
					(size 1.27 1.27)
				)
				(justify mirror)
			)
		)
		(property "Value" ""
			(at 0 0 0)
			(layer "B.Fab")
			(effects
				(font
					(size 1.27 1.27)
				)
				(justify mirror)
			)
		)
		(duplicate_pad_numbers_are_jumpers no)
		(fp_line
			(start 0.7874 0.4064)
			(end 0.7874 -0.4064)
			(stroke
				(width 0.1524)
				(type default)
			)
			(layer "B.SilkS")
		)
		(fp_line
			(start 0.7874 -0.4064)
			(end -0.7874 -0.4064)
			(stroke
				(width 0.1524)
				(type default)
			)
			(layer "B.SilkS")
		)
		(fp_line
			(start -0.7874 0.4064)
			(end 0.7874 0.4064)
			(stroke
				(width 0.1524)
				(type default)
			)
			(layer "B.SilkS")
		)
		(fp_line
			(start -0.7874 -0.4064)
			(end -0.7874 0.4064)
			(stroke
				(width 0.1524)
				(type default)
			)
			(layer "B.SilkS")
		)
		(fp_line
			(start 0.67945 0.3048)
			(end 0.67945 -0.305054)
			(stroke
				(width 0.1)
				(type default)
			)
			(layer "B.Fab")
		)
		(fp_line
			(start 0.67945 -0.305054)
			(end 0.12065 -0.305054)
			(stroke
				(width 0.1)
				(type default)
			)
			(layer "B.Fab")
		)
		(fp_line
			(start 0.12065 0.3048)
			(end 0.67945 0.3048)
			(stroke
				(width 0.1)
				(type default)
			)
			(layer "B.Fab")
		)
		(fp_line
			(start 0.12065 0.2794)
			(end 0.12065 0.3048)
			(stroke
				(width 0.1)
				(type default)
			)
			(layer "B.Fab")
		)
		(fp_line
			(start 0.12065 -0.2794)
			(end -0.12065 -0.2794)
			(stroke
				(width 0.1)
				(type default)
			)
			(layer "B.Fab")
		)
		(fp_line
			(start 0.12065 -0.305054)
			(end 0.12065 -0.2794)
			(stroke
				(width 0.1)
				(type default)
			)
			(layer "B.Fab")
		)
		(fp_line
			(start -0.120396 0.3048)
			(end -0.120396 0.2794)
			(stroke
				(width 0.1)
				(type default)
			)
			(layer "B.Fab")
		)
		(fp_line
			(start -0.120396 0.2794)
			(end 0.12065 0.2794)
			(stroke
				(width 0.1)
				(type default)
			)
			(layer "B.Fab")
		)
		(fp_line
			(start -0.12065 -0.2794)
			(end -0.12065 -0.3048)
			(stroke
				(width 0.1)
				(type default)
			)
			(layer "B.Fab")
		)
		(fp_line
			(start -0.12065 -0.3048)
			(end -0.67945 -0.3048)
			(stroke
				(width 0.1)
				(type default)
			)
			(layer "B.Fab")
		)
		(fp_line
			(start -0.67945 0.3048)
			(end -0.120396 0.3048)
			(stroke
				(width 0.1)
				(type default)
			)
			(layer "B.Fab")
		)
		(fp_line
			(start -0.67945 -0.3048)
			(end -0.67945 0.3048)
			(stroke
				(width 0.1)
				(type default)
			)
			(layer "B.Fab")
		)
		(pad "1" smd circle
			(at 0.40005 0)
			(size 0 0)
			(layers "B.Cu" "B.Mask" "B.Paste")
			(net "P3V3_AUX")
		)
		(pad "2" smd circle
			(at -0.40005 0)
			(size 0 0)
			(layers "B.Cu" "B.Mask" "B.Paste")
			(net "GND")
		)
	)
	(footprint ""
		(layer "B.Cu")
		(at 244.099842 -382.936242 90)
		(property "Reference" "PC1751"
			(at 0 0 90)
			(layer "B.SilkS")
			(hide yes)
			(effects
				(font
					(size 1.27 1.27)
				)
				(justify mirror)
			)
		)
		(property "Value" ""
			(at 0 0 90)
			(layer "B.Fab")
			(effects
				(font
					(size 1.27 1.27)
				)
				(justify mirror)
			)
		)
		(duplicate_pad_numbers_are_jumpers no)
		(fp_line
			(start 0.7874 -0.4064)
			(end -0.7874 -0.4064)
			(stroke
				(width 0.1524)
				(type default)
			)
			(layer "B.SilkS")
		)
		(fp_line
			(start -0.7874 -0.4064)
			(end -0.7874 0.4064)
			(stroke
				(width 0.1524)
				(type default)
			)
			(layer "B.SilkS")
		)
		(fp_line
			(start 0.7874 0.4064)
			(end 0.7874 -0.4064)
			(stroke
				(width 0.1524)
				(type default)
			)
			(layer "B.SilkS")
		)
		(fp_line
			(start -0.7874 0.4064)
			(end 0.7874 0.4064)
			(stroke
				(width 0.1524)
				(type default)
			)
			(layer "B.SilkS")
		)
		(fp_line
			(start 0.67945 -0.305054)
			(end 0.12065 -0.305054)
			(stroke
				(width 0.1)
				(type default)
			)
			(layer "B.Fab")
		)
		(fp_line
			(start 0.12065 -0.305054)
			(end 0.12065 -0.2794)
			(stroke
				(width 0.1)
				(type default)
			)
			(layer "B.Fab")
		)
		(fp_line
			(start -0.12065 -0.3048)
			(end -0.67945 -0.3048)
			(stroke
				(width 0.1)
				(type default)
			)
			(layer "B.Fab")
		)
		(fp_line
			(start -0.67945 -0.3048)
			(end -0.67945 0.3048)
			(stroke
				(width 0.1)
				(type default)
			)
			(layer "B.Fab")
		)
		(fp_line
			(start 0.12065 -0.2794)
			(end -0.12065 -0.2794)
			(stroke
				(width 0.1)
				(type default)
			)
			(layer "B.Fab")
		)
		(fp_line
			(start -0.12065 -0.2794)
			(end -0.12065 -0.3048)
			(stroke
				(width 0.1)
				(type default)
			)
			(layer "B.Fab")
		)
		(fp_line
			(start 0.12065 0.2794)
			(end 0.12065 0.3048)
			(stroke
				(width 0.1)
				(type default)
			)
			(layer "B.Fab")
		)
		(fp_line
			(start -0.120396 0.2794)
			(end 0.12065 0.2794)
			(stroke
				(width 0.1)
				(type default)
			)
			(layer "B.Fab")
		)
		(fp_line
			(start 0.67945 0.3048)
			(end 0.67945 -0.305054)
			(stroke
				(width 0.1)
				(type default)
			)
			(layer "B.Fab")
		)
		(fp_line
			(start 0.12065 0.3048)
			(end 0.67945 0.3048)
			(stroke
				(width 0.1)
				(type default)
			)
			(layer "B.Fab")
		)
		(fp_line
			(start -0.120396 0.3048)
			(end -0.120396 0.2794)
			(stroke
				(width 0.1)
				(type default)
			)
			(layer "B.Fab")
		)
		(fp_line
			(start -0.67945 0.3048)
			(end -0.120396 0.3048)
			(stroke
				(width 0.1)
				(type default)
			)
			(layer "B.Fab")
		)
		(pad "1" smd circle
			(at 0.40005 0 270)
			(size 0 0)
			(layers "B.Cu" "B.Mask" "B.Paste")
			(net "P12V_HSC_GATE_RC")
		)
		(pad "2" smd circle
			(at -0.40005 0 270)
			(size 0 0)
			(layers "B.Cu" "B.Mask" "B.Paste")
			(net "P12V_HSC_GATE2")
		)
	)
	(footprint ""
		(layer "B.Cu")
		(at 231.775 -243.2431 -90)
		(property "Reference" "R325"
			(at 0 0 90)
			(layer "B.SilkS")
			(hide yes)
			(effects
				(font
					(size 1.27 1.27)
				)
				(justify mirror)
			)
		)
		(property "Value" ""
			(at 0 0 90)
			(layer "B.Fab")
			(effects
				(font
					(size 1.27 1.27)
				)
				(justify mirror)
			)
		)
		(duplicate_pad_numbers_are_jumpers no)
		(fp_line
			(start -0.7874 0.4064)
			(end 0.7874 0.4064)
			(stroke
				(width 0.1524)
				(type default)
			)
			(layer "B.SilkS")
		)
		(fp_line
			(start 0.7874 0.4064)
			(end 0.7874 -0.4064)
			(stroke
				(width 0.1524)
				(type default)
			)
			(layer "B.SilkS")
		)
		(fp_line
			(start -0.7874 -0.4064)
			(end -0.7874 0.4064)
			(stroke
				(width 0.1524)
				(type default)
			)
			(layer "B.SilkS")
		)
		(fp_line
			(start 0.7874 -0.4064)
			(end -0.7874 -0.4064)
			(stroke
				(width 0.1524)
				(type default)
			)
			(layer "B.SilkS")
		)
		(fp_line
			(start -0.67945 0.3048)
			(end -0.120396 0.3048)
			(stroke
				(width 0.1)
				(type default)
			)
			(layer "B.Fab")
		)
		(fp_line
			(start -0.120396 0.3048)
			(end -0.120396 0.2794)
			(stroke
				(width 0.1)
				(type default)
			)
			(layer "B.Fab")
		)
		(fp_line
			(start 0.12065 0.3048)
			(end 0.67945 0.3048)
			(stroke
				(width 0.1)
				(type default)
			)
			(layer "B.Fab")
		)
		(fp_line
			(start 0.67945 0.3048)
			(end 0.67945 -0.305054)
			(stroke
				(width 0.1)
				(type default)
			)
			(layer "B.Fab")
		)
		(fp_line
			(start -0.120396 0.2794)
			(end 0.12065 0.2794)
			(stroke
				(width 0.1)
				(type default)
			)
			(layer "B.Fab")
		)
		(fp_line
			(start 0.12065 0.2794)
			(end 0.12065 0.3048)
			(stroke
				(width 0.1)
				(type default)
			)
			(layer "B.Fab")
		)
		(fp_line
			(start -0.12065 -0.2794)
			(end -0.12065 -0.3048)
			(stroke
				(width 0.1)
				(type default)
			)
			(layer "B.Fab")
		)
		(fp_line
			(start 0.12065 -0.2794)
			(end -0.12065 -0.2794)
			(stroke
				(width 0.1)
				(type default)
			)
			(layer "B.Fab")
		)
		(fp_line
			(start -0.67945 -0.3048)
			(end -0.67945 0.3048)
			(stroke
				(width 0.1)
				(type default)
			)
			(layer "B.Fab")
		)
		(fp_line
			(start -0.12065 -0.3048)
			(end -0.67945 -0.3048)
			(stroke
				(width 0.1)
				(type default)
			)
			(layer "B.Fab")
		)
		(fp_line
			(start 0.12065 -0.305054)
			(end 0.12065 -0.2794)
			(stroke
				(width 0.1)
				(type default)
			)
			(layer "B.Fab")
		)
		(fp_line
			(start 0.67945 -0.305054)
			(end 0.12065 -0.305054)
			(stroke
				(width 0.1)
				(type default)
			)
			(layer "B.Fab")
		)
		(pad "1" smd rect
			(at 0.40005 0 270)
			(size 0.4572 0.508)
			(layers "B.Cu" "B.Mask" "B.Paste")
			(net "SMB_CPU0_CPU1_APML_SCL_R2")
		)
		(pad "2" smd rect
			(at -0.40005 0 270)
			(size 0.4572 0.508)
			(layers "B.Cu" "B.Mask" "B.Paste")
			(net "SMB_CPU0_CPU1_APML_MUX2_SCL")
		)
	)
)
